(kicad_pcb
	(version 20240108)
	(generator "pcbnew")
	(generator_version "8.0")
	(general
		(thickness 1.62)
		(legacy_teardrops no)
	)
	(paper "A4")
	(title_block
		(title "Jetson Orin Baseboard")
		(date "2025-03-12")
		(rev "1.3.4")
		(company "Antmicro Ltd")
		(comment 1 "www.antmicro.com")
		(comment 9 "footprints 570-574 of 677")
	)
	(layers
		(0 "F.Cu" signal)
		(1 "In1.Cu" signal)
		(2 "In2.Cu" signal)
		(3 "In3.Cu" signal)
		(4 "In4.Cu" jumper)
		(5 "In5.Cu" signal)
		(6 "In6.Cu" signal)
		(31 "B.Cu" signal)
		(32 "B.Adhes" user "B.Adhesive")
		(33 "F.Adhes" user "F.Adhesive")
		(34 "B.Paste" user)
		(35 "F.Paste" user)
		(36 "B.SilkS" user "B.Silkscreen")
		(37 "F.SilkS" user "F.Silkscreen")
		(38 "B.Mask" user)
		(39 "F.Mask" user)
		(40 "Dwgs.User" user "User.Drawings")
		(41 "Cmts.User" user "User.Comments")
		(42 "Eco1.User" user "User.Eco1")
		(43 "Eco2.User" user "User.Eco2")
		(44 "Edge.Cuts" user)
		(45 "Margin" user)
		(46 "B.CrtYd" user "B.Courtyard")
		(47 "F.CrtYd" user "F.Courtyard")
		(48 "B.Fab" user)
		(49 "F.Fab" user)
	)
	(footprint "antmicro-footprints:R_0402_1005Metric"
		(layer "B.Cu")
		(at 88.7 106.6 -90)
		(descr "Resistor SMD 0402")
		(tags "resistor SMD 0402")
		(property "Reference" "R193"
			(at -4.1 3.8 90)
			(layer "B.SilkS")
			(effects
				(font
					(size 0.7 0.7)
					(thickness 0.15)
				)
				(justify left bottom mirror)
			)
		)
		(property "Value" "R_10k_0402"
			(at 0 -1.4 90)
			(layer "B.Fab")
			(effects
				(font
					(size 0.7 0.7)
					(thickness 0.15)
				)
				(justify left bottom mirror)
			)
		)
		(property "Footprint" "antmicro-footprints:R_0402_1005Metric"
			(at 0 0 -90)
			(layer "F.Fab")
			(hide yes)
			(effects
				(font
					(size 1.27 1.27)
					(thickness 0.15)
				)
			)
		)
		(property "Datasheet" "https://www.bourns.com/docs/product-datasheets/cr.pdf"
			(at 0 0 -90)
			(layer "F.Fab")
			(hide yes)
			(effects
				(font
					(size 1.27 1.27)
					(thickness 0.15)
				)
			)
		)
		(property "Author" "Antmicro"
			(at -17.9 195.3 0)
			(layer "B.Fab")
			(hide yes)
			(effects
				(font
					(size 1 1)
					(thickness 0.15)
				)
				(justify mirror)
			)
		)
		(property "License" "Apache-2.0"
			(at -17.9 195.3 0)
			(layer "B.Fab")
			(hide yes)
			(effects
				(font
					(size 1 1)
					(thickness 0.15)
				)
				(justify mirror)
			)
		)
		(property "MPN" "CR0402-FX-1002GLF"
			(at -17.9 195.3 0)
			(layer "B.Fab")
			(hide yes)
			(effects
				(font
					(size 1 1)
					(thickness 0.15)
				)
				(justify mirror)
			)
		)
		(property "Manufacturer" "Bourns"
			(at -17.9 195.3 0)
			(layer "B.Fab")
			(hide yes)
			(effects
				(font
					(size 1 1)
					(thickness 0.15)
				)
				(justify mirror)
			)
		)
		(property "Tolerance" "1%"
			(at -17.9 195.3 0)
			(layer "B.Fab")
			(hide yes)
			(effects
				(font
					(size 1 1)
					(thickness 0.15)
				)
				(justify mirror)
			)
		)
		(property "Val" "10k"
			(at -17.9 195.3 0)
			(layer "B.Fab")
			(hide yes)
			(effects
				(font
					(size 1 1)
					(thickness 0.15)
				)
				(justify mirror)
			)
		)
		(sheetname "CSI")
		(sheetfile "csi.kicad_sch")
		(attr smd exclude_from_pos_files exclude_from_bom dnp)
		(fp_rect
			(start -0.925 0.47)
			(end 0.925 -0.47)
			(stroke
				(width 0.05)
				(type default)
			)
			(fill none)
			(layer "B.CrtYd")
		)
		(fp_rect
			(start -0.5 0.25)
			(end 0.5 -0.25)
			(stroke
				(width 0.15)
				(type solid)
			)
			(fill none)
			(layer "B.Fab")
		)
		(fp_text user "${REFERENCE}"
			(at -0.95 -3.168 90)
			(layer "B.Fab")
			(hide yes)
			(effects
				(font
					(size 0.7 0.7)
					(thickness 0.15)
				)
				(justify left bottom mirror)
			)
		)
		(fp_text user "Author: Antmicro"
			(at -0.95 -4.169 90)
			(layer "B.Fab")
			(hide yes)
			(effects
				(font
					(size 0.7 0.7)
					(thickness 0.15)
				)
				(justify left bottom mirror)
			)
		)
		(fp_text user "License: Apache-2.0"
			(at -0.95 -5.169 90)
			(layer "B.Fab")
			(hide yes)
			(effects
				(font
					(size 0.7 0.7)
					(thickness 0.15)
				)
				(justify left bottom mirror)
			)
		)
		(pad "1" smd roundrect
			(at -0.48 0 270)
			(size 0.59 0.64)
			(layers "B.Cu" "B.Paste" "B.Mask")
			(roundrect_rratio 0.25)
			(net 322 "CSIA_PEN")
			(pintype "passive")
		)
		(pad "2" smd roundrect
			(at 0.48 0 270)
			(size 0.59 0.64)
			(layers "B.Cu" "B.Paste" "B.Mask")
			(roundrect_rratio 0.25)
			(net 87 "+3V3")
			(pintype "passive")
		)
	)
	(footprint "antmicro-footprints:R_0402_1005Metric"
		(layer "B.Cu")
		(at 43.77 123.47 90)
		(descr "Resistor SMD 0402")
		(tags "resistor SMD 0402")
		(property "Reference" "R72"
			(at -2.18 -0.82 -90)
			(layer "B.SilkS")
			(effects
				(font
					(size 0.7 0.7)
					(thickness 0.15)
				)
				(justify left bottom mirror)
			)
		)
		(property "Value" "R_200R_0402"
			(at 0 -1.4 -90)
			(layer "B.Fab")
			(effects
				(font
					(size 0.7 0.7)
					(thickness 0.15)
				)
				(justify left bottom mirror)
			)
		)
		(property "Footprint" "antmicro-footprints:R_0402_1005Metric"
			(at 0 0 90)
			(layer "F.Fab")
			(hide yes)
			(effects
				(font
					(size 1.27 1.27)
					(thickness 0.15)
				)
			)
		)
		(property "Datasheet" "https://www.bourns.com/docs/product-datasheets/cr.pdf"
			(at 0 0 90)
			(layer "F.Fab")
			(hide yes)
			(effects
				(font
					(size 1.27 1.27)
					(thickness 0.15)
				)
			)
		)
		(property "Author" "Antmicro"
			(at 167.24 79.7 0)
			(layer "B.Fab")
			(hide yes)
			(effects
				(font
					(size 1 1)
					(thickness 0.15)
				)
				(justify mirror)
			)
		)
		(property "License" "Apache-2.0"
			(at 167.24 79.7 0)
			(layer "B.Fab")
			(hide yes)
			(effects
				(font
					(size 1 1)
					(thickness 0.15)
				)
				(justify mirror)
			)
		)
		(property "MPN" "CR0402-FX-2000GLF"
			(at 167.24 79.7 0)
			(layer "B.Fab")
			(hide yes)
			(effects
				(font
					(size 1 1)
					(thickness 0.15)
				)
				(justify mirror)
			)
		)
		(property "Manufacturer" "Bourns"
			(at 167.24 79.7 0)
			(layer "B.Fab")
			(hide yes)
			(effects
				(font
					(size 1 1)
					(thickness 0.15)
				)
				(justify mirror)
			)
		)
		(property "Tolerance" "1%"
			(at 167.24 79.7 0)
			(layer "B.Fab")
			(hide yes)
			(effects
				(font
					(size 1 1)
					(thickness 0.15)
				)
				(justify mirror)
			)
		)
		(property "Val" "200R"
			(at 167.24 79.7 0)
			(layer "B.Fab")
			(hide yes)
			(effects
				(font
					(size 1 1)
					(thickness 0.15)
				)
				(justify mirror)
			)
		)
		(sheetname "USB Debug, DP")
		(sheetfile "usb.kicad_sch")
		(attr smd)
		(fp_rect
			(start -0.925 0.47)
			(end 0.925 -0.47)
			(stroke
				(width 0.05)
				(type default)
			)
			(fill none)
			(layer "B.CrtYd")
		)
		(fp_rect
			(start -0.5 0.25)
			(end 0.5 -0.25)
			(stroke
				(width 0.15)
				(type solid)
			)
			(fill none)
			(layer "B.Fab")
		)
		(fp_text user "Author: Antmicro"
			(at -0.95 -4.169 -90)
			(layer "B.Fab")
			(hide yes)
			(effects
				(font
					(size 0.7 0.7)
					(thickness 0.15)
				)
				(justify left bottom mirror)
			)
		)
		(fp_text user "License: Apache-2.0"
			(at -0.95 -5.169 -90)
			(layer "B.Fab")
			(hide yes)
			(effects
				(font
					(size 0.7 0.7)
					(thickness 0.15)
				)
				(justify left bottom mirror)
			)
		)
		(fp_text user "${REFERENCE}"
			(at -0.95 -3.168 -90)
			(layer "B.Fab")
			(hide yes)
			(effects
				(font
					(size 0.7 0.7)
					(thickness 0.15)
				)
				(justify left bottom mirror)
			)
		)
		(pad "1" smd roundrect
			(at -0.48 0 90)
			(size 0.59 0.64)
			(layers "B.Cu" "B.Paste" "B.Mask")
			(roundrect_rratio 0.25)
			(net 142 "Net-(D2-A)")
			(pintype "passive")
		)
		(pad "2" smd roundrect
			(at 0.48 0 90)
			(size 0.59 0.64)
			(layers "B.Cu" "B.Paste" "B.Mask")
			(roundrect_rratio 0.25)
			(net 185 "/USB Debug, DP/FTDI_3V3")
			(pintype "passive")
		)
	)
	(footprint "antmicro-footprints:R_0603_1608Metric"
		(layer "B.Cu")
		(at 50.05 91.35)
		(descr "Resistor SMD 0603")
		(tags "resistor SMD 0603")
		(property "Reference" "R196"
			(at -1.1 0 180)
			(layer "B.SilkS")
			(effects
				(font
					(size 0.7 0.7)
					(thickness 0.15)
				)
				(justify left bottom mirror)
			)
		)
		(property "Value" "R_63R4_0603"
			(at 0 -1.6 180)
			(layer "B.Fab")
			(effects
				(font
					(size 0.7 0.7)
					(thickness 0.15)
				)
				(justify left bottom mirror)
			)
		)
		(property "Footprint" "antmicro-footprints:R_0603_1608Metric"
			(at 0 0 0)
			(layer "F.Fab")
			(hide yes)
			(effects
				(font
					(size 1.27 1.27)
					(thickness 0.15)
				)
			)
		)
		(property "Datasheet" "https://www.bourns.com/docs/product-datasheets/cr.pdf"
			(at 0 0 0)
			(layer "F.Fab")
			(hide yes)
			(effects
				(font
					(size 1.27 1.27)
					(thickness 0.15)
				)
			)
		)
		(property "Author" "Antmicro"
			(at 0 0 0)
			(layer "B.Fab")
			(hide yes)
			(effects
				(font
					(size 1 1)
					(thickness 0.15)
				)
				(justify mirror)
			)
		)
		(property "License" "Apache-2.0"
			(at 0 0 0)
			(layer "B.Fab")
			(hide yes)
			(effects
				(font
					(size 1 1)
					(thickness 0.15)
				)
				(justify mirror)
			)
		)
		(property "MPN" "CR0603-FX-63R4ELF"
			(at 0 0 0)
			(layer "B.Fab")
			(hide yes)
			(effects
				(font
					(size 1 1)
					(thickness 0.15)
				)
				(justify mirror)
			)
		)
		(property "Manufacturer" "Bourns"
			(at 0 0 0)
			(layer "B.Fab")
			(hide yes)
			(effects
				(font
					(size 1 1)
					(thickness 0.15)
				)
				(justify mirror)
			)
		)
		(property "Tolerance" "1%"
			(at 0 0 0)
			(layer "B.Fab")
			(hide yes)
			(effects
				(font
					(size 1 1)
					(thickness 0.15)
				)
				(justify mirror)
			)
		)
		(property "Val" "63R4"
			(at 0 0 0)
			(layer "B.Fab")
			(hide yes)
			(effects
				(font
					(size 1 1)
					(thickness 0.15)
				)
				(justify mirror)
			)
		)
		(sheetname "Ethernet")
		(sheetfile "ethernet.kicad_sch")
		(attr smd)
		(fp_line
			(start 0.15 -0.4)
			(end -0.15 -0.4)
			(stroke
				(width 0.15)
				(type solid)
			)
			(layer "B.SilkS")
		)
		(fp_line
			(start 0.15 0.4)
			(end -0.15 0.4)
			(stroke
				(width 0.15)
				(type solid)
			)
			(layer "B.SilkS")
		)
		(fp_rect
			(start -1.25 0.65)
			(end 1.25 -0.65)
			(stroke
				(width 0.05)
				(type solid)
			)
			(fill none)
			(layer "B.CrtYd")
		)
		(fp_rect
			(start -0.8 0.4)
			(end 0.8 -0.4)
			(stroke
				(width 0.15)
				(type solid)
			)
			(fill none)
			(layer "B.Fab")
		)
		(fp_text user "Author: Antmicro"
			(at -1.25 -4.9 180)
			(layer "B.Fab")
			(hide yes)
			(effects
				(font
					(size 0.7 0.7)
					(thickness 0.15)
				)
				(justify left bottom mirror)
			)
		)
		(fp_text user "${REFERENCE}"
			(at -1.25 -3.898 180)
			(layer "B.Fab")
			(hide yes)
			(effects
				(font
					(size 0.7 0.7)
					(thickness 0.15)
				)
				(justify left bottom mirror)
			)
		)
		(fp_text user "License: Apache-2.0"
			(at -1.25 -5.9 180)
			(layer "B.Fab")
			(hide yes)
			(effects
				(font
					(size 0.7 0.7)
					(thickness 0.15)
				)
				(justify left bottom mirror)
			)
		)
		(pad "1" smd roundrect
			(at -0.7 0)
			(size 0.8 1)
			(layers "B.Cu" "B.Paste" "B.Mask")
			(roundrect_rratio 0.2)
			(net 499 "/Ethernet/VSS")
			(pintype "passive")
		)
		(pad "2" smd roundrect
			(at 0.7 0)
			(size 0.8 1)
			(layers "B.Cu" "B.Paste" "B.Mask")
			(roundrect_rratio 0.2)
			(net 568 "/Ethernet/CLSA")
			(pintype "passive")
		)
	)
	(footprint "antmicro-footprints:C_0603_1608Metric"
		(layer "B.Cu")
		(at 114.5 95 180)
		(descr "Capacitor SMD 0603")
		(tags "capacitor 0603")
		(property "Reference" "C24"
			(at -1.1 -1.5 0)
			(layer "B.SilkS")
			(effects
				(font
					(size 0.7 0.7)
					(thickness 0.15)
				)
				(justify left bottom mirror)
			)
		)
		(property "Value" "C_10u_0603"
			(at 0 -1.6 0)
			(layer "B.Fab")
			(effects
				(font
					(size 0.7 0.7)
					(thickness 0.15)
				)
				(justify left bottom mirror)
			)
		)
		(property "Footprint" "antmicro-footprints:C_0603_1608Metric"
			(at 0 0 180)
			(layer "F.Fab")
			(hide yes)
			(effects
				(font
					(size 1.27 1.27)
					(thickness 0.15)
				)
			)
		)
		(property "Datasheet" "https://www.murata.com/products/productdetail?partno=GRM188R61A106KE69%23"
			(at 0 0 180)
			(layer "F.Fab")
			(hide yes)
			(effects
				(font
					(size 1.27 1.27)
					(thickness 0.15)
				)
			)
		)
		(property "Author" "Antmicro"
			(at 229 190 0)
			(layer "B.Fab")
			(hide yes)
			(effects
				(font
					(size 1 1)
					(thickness 0.15)
				)
				(justify mirror)
			)
		)
		(property "Dielectric" "template_dielectric"
			(at 229 190 0)
			(layer "B.Fab")
			(hide yes)
			(effects
				(font
					(size 1 1)
					(thickness 0.15)
				)
				(justify mirror)
			)
		)
		(property "License" "Apache-2.0"
			(at 229 190 0)
			(layer "B.Fab")
			(hide yes)
			(effects
				(font
					(size 1 1)
					(thickness 0.15)
				)
				(justify mirror)
			)
		)
		(property "MPN" "GRM188R61A106KE69D"
			(at 229 190 0)
			(layer "B.Fab")
			(hide yes)
			(effects
				(font
					(size 1 1)
					(thickness 0.15)
				)
				(justify mirror)
			)
		)
		(property "Manufacturer" "Murata"
			(at 229 190 0)
			(layer "B.Fab")
			(hide yes)
			(effects
				(font
					(size 1 1)
					(thickness 0.15)
				)
				(justify mirror)
			)
		)
		(property "Val" "10u"
			(at 229 190 0)
			(layer "B.Fab")
			(hide yes)
			(effects
				(font
					(size 1 1)
					(thickness 0.15)
				)
				(justify mirror)
			)
		)
		(property "Voltage" ""
			(at 229 190 0)
			(layer "B.Fab")
			(hide yes)
			(effects
				(font
					(size 1 1)
					(thickness 0.15)
				)
				(justify mirror)
			)
		)
		(sheetname "M.2")
		(sheetfile "m-2.kicad_sch")
		(attr smd)
		(fp_line
			(start 0.15 0.4)
			(end -0.15 0.4)
			(stroke
				(width 0.15)
				(type solid)
			)
			(layer "B.SilkS")
		)
		(fp_line
			(start 0.15 -0.4)
			(end -0.15 -0.4)
			(stroke
				(width 0.15)
				(type solid)
			)
			(layer "B.SilkS")
		)
		(fp_rect
			(start -1.25 0.65)
			(end 1.25 -0.65)
			(stroke
				(width 0.05)
				(type solid)
			)
			(fill none)
			(layer "B.CrtYd")
		)
		(fp_rect
			(start -0.8 0.4)
			(end 0.8 -0.4)
			(stroke
				(width 0.15)
				(type solid)
			)
			(fill none)
			(layer "B.Fab")
		)
		(fp_text user "License: Apache-2.0"
			(at -1.682 -5.895 0)
			(layer "B.Fab")
			(hide yes)
			(effects
				(font
					(size 0.7 0.7)
					(thickness 0.15)
				)
				(justify left bottom mirror)
			)
		)
		(fp_text user "Author: Antmicro"
			(at -1.682 -4.894 0)
			(layer "B.Fab")
			(hide yes)
			(effects
				(font
					(size 0.7 0.7)
					(thickness 0.15)
				)
				(justify left bottom mirror)
			)
		)
		(fp_text user "${REFERENCE}"
			(at -1.682 -3.895 0)
			(layer "B.Fab")
			(hide yes)
			(effects
				(font
					(size 0.7 0.7)
					(thickness 0.15)
				)
				(justify left bottom mirror)
			)
		)
		(pad "1" smd roundrect
			(at -0.7 0 180)
			(size 0.8 1)
			(layers "B.Cu" "B.Paste" "B.Mask")
			(roundrect_rratio 0.2)
			(net 635 "/M.2/3V3_M2")
			(pintype "passive")
		)
		(pad "2" smd roundrect
			(at 0.7 0 180)
			(size 0.8 1)
			(layers "B.Cu" "B.Paste" "B.Mask")
			(roundrect_rratio 0.2)
			(net 1 "GND")
			(pintype "passive")
		)
	)
	(footprint "antmicro-footprints:SOT-523"
		(layer "B.Cu")
		(at 47.825 116.75)
		(property "Reference" "Q20"
			(at -15.065 10.38 0)
			(layer "B.SilkS")
			(effects
				(font
					(size 0.7 0.7)
					(thickness 0.15)
				)
				(justify right bottom mirror)
			)
		)
		(property "Value" "PJE138K"
			(at 0.1 -1.824 0)
			(layer "B.Fab")
			(effects
				(font
					(size 0.7 0.7)
					(thickness 0.15)
				)
				(justify right bottom mirror)
			)
		)
		(property "Footprint" "antmicro-footprints:SOT-523"
			(at 0 0 0)
			(layer "F.Fab")
			(hide yes)
			(effects
				(font
					(size 1.27 1.27)
					(thickness 0.15)
				)
			)
		)
		(property "Datasheet" "https://www.mouser.com/datasheet/2/1057/PJE138K-1876698.pdf"
			(at 0 0 0)
			(layer "F.Fab")
			(hide yes)
			(effects
				(font
					(size 1.27 1.27)
					(thickness 0.15)
				)
			)
		)
		(property "Author" "Antmicro"
			(at 0 0 0)
			(layer "B.Fab")
			(hide yes)
			(effects
				(font
					(size 1 1)
					(thickness 0.15)
				)
				(justify mirror)
			)
		)
		(property "License" "Apache-2.0"
			(at 0 0 0)
			(layer "B.Fab")
			(hide yes)
			(effects
				(font
					(size 1 1)
					(thickness 0.15)
				)
				(justify mirror)
			)
		)
		(property "MPN" "PJE138K_R1_00001"
			(at 0 0 0)
			(layer "B.Fab")
			(hide yes)
			(effects
				(font
					(size 1 1)
					(thickness 0.15)
				)
				(justify mirror)
			)
		)
		(property "Manufacturer" "PANJIT"
			(at 0 0 0)
			(layer "B.Fab")
			(hide yes)
			(effects
				(font
					(size 1 1)
					(thickness 0.15)
				)
				(justify mirror)
			)
		)
		(sheetname "USB Debug, DP")
		(sheetfile "usb.kicad_sch")
		(attr smd)
		(fp_line
			(start -0.927 0.351)
			(end -0.927 0.051)
			(stroke
				(width 0.15)
				(type solid)
			)
			(layer "B.SilkS")
		)
		(fp_line
			(start -0.725 0.551)
			(end -0.927 0.351)
			(stroke
				(width 0.15)
				(type solid)
			)
			(layer "B.SilkS")
		)
		(fp_line
			(start -0.277 0.551)
			(end -0.725 0.551)
			(stroke
				(width 0.15)
				(type solid)
			)
			(layer "B.SilkS")
		)
		(fp_line
			(start -0.277 0.75)
			(end -0.277 0.551)
			(stroke
				(width 0.15)
				(type solid)
			)
			(layer "B.SilkS")
		)
		(fp_circle
			(center -0.9652 -0.9652)
			(end -0.9152 -0.9652)
			(stroke
				(width 0.15)
				(type solid)
			)
			(fill solid)
			(layer "B.SilkS")
		)
		(fp_line
			(start -1.12 -1.15)
			(end -1.12 1.16)
			(stroke
				(width 0.05)
				(type solid)
			)
			(layer "B.CrtYd")
		)
		(fp_line
			(start 1.1 -1.15)
			(end -1.12 -1.15)
			(stroke
				(width 0.05)
				(type solid)
			)
			(layer "B.CrtYd")
		)
		(fp_line
			(start 1.1 -1.15)
			(end 1.1 1.16)
			(stroke
				(width 0.05)
				(type solid)
			)
			(layer "B.CrtYd")
		)
		(fp_line
			(start 1.1 1.16)
			(end -1.12 1.16)
			(stroke
				(width 0.05)
				(type solid)
			)
			(layer "B.CrtYd")
		)
		(fp_line
			(start -0.802 -0.424)
			(end -0.802 0.276)
			(stroke
				(width 0.15)
				(type solid)
			)
			(layer "B.Fab")
		)
		(fp_line
			(start -0.802 -0.424)
			(end 0.8 -0.424)
			(stroke
				(width 0.15)
				(type solid)
			)
			(layer "B.Fab")
		)
		(fp_line
			(start -0.802 0.276)
			(end -0.652 0.425)
			(stroke
				(width 0.15)
				(type solid)
			)
			(layer "B.Fab")
		)
		(fp_line
			(start -0.652 0.425)
			(end 0.8 0.425)
			(stroke
				(width 0.15)
				(type solid)
			)
			(layer "B.Fab")
		)
		(fp_line
			(start 0.8 -0.424)
			(end 0.8 0.425)
			(stroke
				(width 0.15)
				(type solid)
			)
			(layer "B.Fab")
		)
		(fp_circle
			(center -0.9652 -0.9652)
			(end -0.9144 -0.9652)
			(stroke
				(width 0.15)
				(type solid)
			)
			(fill none)
			(layer "B.Fab")
		)
		(fp_text user "License: Apache-2.0"
			(at -1.12 -5.024 0)
			(layer "B.Fab")
			(hide yes)
			(effects
				(font
					(size 0.7 0.7)
					(thickness 0.15)
				)
				(justify right bottom mirror)
			)
		)
		(fp_text user "${REFERENCE}"
			(at -1.12 -3.824 0)
			(layer "B.Fab")
			(hide yes)
			(effects
				(font
					(size 0.7 0.7)
					(thickness 0.15)
				)
				(justify right bottom mirror)
			)
		)
		(fp_text user "Author: Antmicro"
			(at -1.12 -6.224 0)
			(layer "B.Fab")
			(hide yes)
			(effects
				(font
					(size 0.7 0.7)
					(thickness 0.15)
				)
				(justify right bottom mirror)
			)
		)
		(pad "1" smd rect
			(at -0.5 -0.65)
			(size 0.4 0.51)
			(layers "B.Cu" "B.Paste" "B.Mask")
			(net 86 "~{RESET}")
			(pinfunction "G")
			(pintype "passive")
		)
		(pad "2" smd rect
			(at 0.498 -0.65)
			(size 0.4 0.51)
			(layers "B.Cu" "B.Paste" "B.Mask")
			(net 1 "GND")
			(pinfunction "S")
			(pintype "passive")
		)
		(pad "3" smd rect
			(at 0 0.652)
			(size 0.4 0.51)
			(layers "B.Cu" "B.Paste" "B.Mask")
			(net 397 "/USB Debug, DP/FTDI_CBUS_EN")
			(pinfunction "D")
			(pintype "passive")
		)
	)
)
